(kicad_pcb
	(version 20260206)
	(generator "pcbnew")
	(generator_version "10.0")
	(general
		(thickness 1.6)
		(legacy_teardrops no)
	)
	(paper "A4")
	(title_block
		(title "01162023_DA0F0TEBIF0_F0T_Expander_BD_F_brd_V02_OCP.brd")
		(comment 1 "Grand Teton / footprints 8127-8134 of 9728")
	)
	(layers
		(0 "F.Cu" signal "TOP")
		(4 "In1.Cu" signal "GND")
		(6 "In2.Cu" signal "VCC")
		(8 "In3.Cu" signal "VCC1")
		(10 "In4.Cu" signal "GND1")
		(12 "In5.Cu" signal "IN1")
		(14 "In6.Cu" signal "GND2")
		(16 "In7.Cu" signal "IN2")
		(18 "In8.Cu" signal "GND3")
		(20 "In9.Cu" signal "IN3")
		(22 "In10.Cu" signal "GND4")
		(24 "In11.Cu" signal "IN4")
		(26 "In12.Cu" signal "GND5")
		(28 "In13.Cu" signal "IN5")
		(30 "In14.Cu" signal "GND6")
		(32 "In15.Cu" signal "IN6")
		(34 "In16.Cu" signal "GND7")
		(2 "B.Cu" signal "BOTTOM")
		(9 "F.Adhes" user "F.Adhesive")
		(11 "B.Adhes" user "B.Adhesive")
		(13 "F.Paste" user "Package Geometry/Pastemask Top")
		(15 "B.Paste" user "Package Geometry/Pastemask Bottom")
		(5 "F.SilkS" user "Ref Des/Silkscreen Top")
		(7 "B.SilkS" user "Ref Des/Silkscreen Bottom")
		(1 "F.Mask" user "Board Geometry/Soldermask Top")
		(3 "B.Mask" user "Board Geometry/Soldermask Bottom")
		(17 "Dwgs.User" user "User.Drawings")
		(19 "Cmts.User" user "User.Comments")
		(21 "Eco1.User" user "User.Eco1")
		(23 "Eco2.User" user "User.Eco2")
		(25 "Edge.Cuts" user "Board Geometry/Outline")
		(27 "Margin" user)
		(31 "F.CrtYd" user "Package Geometry/Place Bound Top")
		(29 "B.CrtYd" user "Package Geometry/Place Bound Bottom")
		(35 "F.Fab" user "Ref Des/Assembly Top")
		(33 "B.Fab" user "Ref Des/Assembly Bottom")
	)
	(footprint ""
		(layer "B.Cu")
		(at 303.077626 -239.976406 90)
		(property "Reference" "R4102"
			(at 0 0 90)
			(layer "B.SilkS")
			(hide yes)
			(effects
				(font
					(size 1.27 1.27)
				)
				(justify mirror)
			)
		)
		(property "Value" ""
			(at 0 0 90)
			(layer "B.Fab")
			(effects
				(font
					(size 1.27 1.27)
				)
				(justify mirror)
			)
		)
		(duplicate_pad_numbers_are_jumpers no)
		(fp_line
			(start 0.7874 -0.4064)
			(end -0.7874 -0.4064)
			(stroke
				(width 0.1524)
				(type default)
			)
			(layer "B.SilkS")
		)
		(fp_line
			(start -0.7874 -0.4064)
			(end -0.7874 0.4064)
			(stroke
				(width 0.1524)
				(type default)
			)
			(layer "B.SilkS")
		)
		(fp_line
			(start 0.7874 0.4064)
			(end 0.7874 -0.4064)
			(stroke
				(width 0.1524)
				(type default)
			)
			(layer "B.SilkS")
		)
		(fp_line
			(start -0.7874 0.4064)
			(end 0.7874 0.4064)
			(stroke
				(width 0.1524)
				(type default)
			)
			(layer "B.SilkS")
		)
		(fp_line
			(start 0.67945 -0.305054)
			(end 0.12065 -0.305054)
			(stroke
				(width 0.1)
				(type default)
			)
			(layer "B.Fab")
		)
		(fp_line
			(start 0.12065 -0.305054)
			(end 0.12065 -0.2794)
			(stroke
				(width 0.1)
				(type default)
			)
			(layer "B.Fab")
		)
		(fp_line
			(start -0.12065 -0.3048)
			(end -0.67945 -0.3048)
			(stroke
				(width 0.1)
				(type default)
			)
			(layer "B.Fab")
		)
		(fp_line
			(start -0.67945 -0.3048)
			(end -0.67945 0.3048)
			(stroke
				(width 0.1)
				(type default)
			)
			(layer "B.Fab")
		)
		(fp_line
			(start 0.12065 -0.2794)
			(end -0.12065 -0.2794)
			(stroke
				(width 0.1)
				(type default)
			)
			(layer "B.Fab")
		)
		(fp_line
			(start -0.12065 -0.2794)
			(end -0.12065 -0.3048)
			(stroke
				(width 0.1)
				(type default)
			)
			(layer "B.Fab")
		)
		(fp_line
			(start 0.12065 0.2794)
			(end 0.12065 0.3048)
			(stroke
				(width 0.1)
				(type default)
			)
			(layer "B.Fab")
		)
		(fp_line
			(start -0.120396 0.2794)
			(end 0.12065 0.2794)
			(stroke
				(width 0.1)
				(type default)
			)
			(layer "B.Fab")
		)
		(fp_line
			(start 0.67945 0.3048)
			(end 0.67945 -0.305054)
			(stroke
				(width 0.1)
				(type default)
			)
			(layer "B.Fab")
		)
		(fp_line
			(start 0.12065 0.3048)
			(end 0.67945 0.3048)
			(stroke
				(width 0.1)
				(type default)
			)
			(layer "B.Fab")
		)
		(fp_line
			(start -0.120396 0.3048)
			(end -0.120396 0.2794)
			(stroke
				(width 0.1)
				(type default)
			)
			(layer "B.Fab")
		)
		(fp_line
			(start -0.67945 0.3048)
			(end -0.120396 0.3048)
			(stroke
				(width 0.1)
				(type default)
			)
			(layer "B.Fab")
		)
		(pad "1" smd circle
			(at 0.40005 0 270)
			(size 0 0)
			(layers "B.Cu" "B.Mask" "B.Paste")
			(net "SMB_MB_BMC_ISO_SDA")
		)
		(pad "2" smd circle
			(at -0.40005 0 270)
			(size 0 0)
			(layers "B.Cu" "B.Mask" "B.Paste")
			(net "P3V3_AUX")
		)
	)
	(footprint ""
		(layer "B.Cu")
		(at 141.793214 -210.857846 -90)
		(property "Reference" "U106"
			(at -0.041656 1.854454 270)
			(unlocked yes)
			(layer "B.SilkS")
			(effects
				(font
					(size 0.7874 0.5842)
					(thickness 0.1524)
				)
				(justify mirror)
			)
		)
		(property "Value" ""
			(at 0 0 90)
			(layer "B.Fab")
			(effects
				(font
					(size 1.27 1.27)
				)
				(justify mirror)
			)
		)
		(duplicate_pad_numbers_are_jumpers no)
		(fp_line
			(start -1.7272 1.1176)
			(end 1.7272 1.1176)
			(stroke
				(width 0.1524)
				(type default)
			)
			(layer "B.SilkS")
		)
		(fp_line
			(start 1.7272 1.1176)
			(end 1.7272 -1.1176)
			(stroke
				(width 0.1524)
				(type default)
			)
			(layer "B.SilkS")
		)
		(fp_line
			(start 0 -0.7366)
			(end 0.254 -1.1176)
			(stroke
				(width 0.1524)
				(type default)
			)
			(layer "B.SilkS")
		)
		(fp_line
			(start -1.7272 -1.1176)
			(end -1.7272 1.1176)
			(stroke
				(width 0.1524)
				(type default)
			)
			(layer "B.SilkS")
		)
		(fp_line
			(start -1.7272 -1.1176)
			(end -0.254 -1.1176)
			(stroke
				(width 0.1524)
				(type default)
			)
			(layer "B.SilkS")
		)
		(fp_line
			(start -0.254 -1.1176)
			(end 0 -0.7366)
			(stroke
				(width 0.1524)
				(type default)
			)
			(layer "B.SilkS")
		)
		(fp_line
			(start 0.254 -1.1176)
			(end 1.7272 -1.1176)
			(stroke
				(width 0.1524)
				(type default)
			)
			(layer "B.SilkS")
		)
		(fp_poly
			(pts
				(xy 1.9558 -0.649986) (xy 2.7178 -0.268986) (xy 2.7178 -1.030986)
			)
			(stroke
				(width 0)
				(type default)
			)
			(fill yes)
			(layer "B.SilkS")
		)
		(fp_line
			(start -1.5748 1.1176)
			(end -1.5748 -1.1176)
			(stroke
				(width 0.1)
				(type default)
			)
			(layer "B.Fab")
		)
		(fp_line
			(start 1.5748 1.1176)
			(end -1.5748 1.1176)
			(stroke
				(width 0.1)
				(type default)
			)
			(layer "B.Fab")
		)
		(fp_line
			(start -1.5748 -1.1176)
			(end 1.5748 -1.1176)
			(stroke
				(width 0.1)
				(type default)
			)
			(layer "B.Fab")
		)
		(fp_line
			(start 1.5748 -1.1176)
			(end 1.5748 1.1176)
			(stroke
				(width 0.1)
				(type default)
			)
			(layer "B.Fab")
		)
		(fp_poly
			(pts
				(xy 1.9558 -0.649986) (xy 2.7178 -0.268986) (xy 2.7178 -1.030986)
			)
			(stroke
				(width 0)
				(type default)
			)
			(fill yes)
			(layer "B.Fab")
		)
		(pad "1" smd rect
			(at 0.999998 -0.649986 180)
			(size 0.3556 1.1176)
			(layers "B.Cu" "B.Mask" "B.Paste")
			(net "UART_PEX2_CLI_R_RX")
		)
		(pad "2" smd rect
			(at 0.999998 0 180)
			(size 0.3556 1.1176)
			(layers "B.Cu" "B.Mask" "B.Paste")
			(net "GND")
		)
		(pad "3" smd rect
			(at 0.999998 0.649986 180)
			(size 0.3556 1.1176)
			(layers "B.Cu" "B.Mask" "B.Paste")
			(net "UART_PEX3_CLI_R_RX")
		)
		(pad "4" smd rect
			(at -0.999998 0.649986 180)
			(size 0.3556 1.1176)
			(layers "B.Cu" "B.Mask" "B.Paste")
			(net "UART_PEX3_CLI_BUF_R_RX")
		)
		(pad "5" smd rect
			(at -0.999998 0 180)
			(size 0.3556 1.1176)
			(layers "B.Cu" "B.Mask" "B.Paste")
			(net "P3V3_AUX")
		)
		(pad "6" smd rect
			(at -0.999998 -0.649986 180)
			(size 0.3556 1.1176)
			(layers "B.Cu" "B.Mask" "B.Paste")
			(net "UART_PEX2_CLI_BUF_R_RX")
		)
	)
	(footprint ""
		(layer "B.Cu")
		(at 226.386644 -231.225598 -90)
		(property "Reference" "R1478"
			(at 0 0 90)
			(layer "B.SilkS")
			(hide yes)
			(effects
				(font
					(size 1.27 1.27)
				)
				(justify mirror)
			)
		)
		(property "Value" ""
			(at 0 0 90)
			(layer "B.Fab")
			(effects
				(font
					(size 1.27 1.27)
				)
				(justify mirror)
			)
		)
		(duplicate_pad_numbers_are_jumpers no)
		(fp_line
			(start -0.7874 0.4064)
			(end 0.7874 0.4064)
			(stroke
				(width 0.1524)
				(type default)
			)
			(layer "B.SilkS")
		)
		(fp_line
			(start 0.7874 0.4064)
			(end 0.7874 -0.4064)
			(stroke
				(width 0.1524)
				(type default)
			)
			(layer "B.SilkS")
		)
		(fp_line
			(start -0.7874 -0.4064)
			(end -0.7874 0.4064)
			(stroke
				(width 0.1524)
				(type default)
			)
			(layer "B.SilkS")
		)
		(fp_line
			(start 0.7874 -0.4064)
			(end -0.7874 -0.4064)
			(stroke
				(width 0.1524)
				(type default)
			)
			(layer "B.SilkS")
		)
		(fp_line
			(start -0.67945 0.3048)
			(end -0.120396 0.3048)
			(stroke
				(width 0.1)
				(type default)
			)
			(layer "B.Fab")
		)
		(fp_line
			(start -0.120396 0.3048)
			(end -0.120396 0.2794)
			(stroke
				(width 0.1)
				(type default)
			)
			(layer "B.Fab")
		)
		(fp_line
			(start 0.12065 0.3048)
			(end 0.67945 0.3048)
			(stroke
				(width 0.1)
				(type default)
			)
			(layer "B.Fab")
		)
		(fp_line
			(start 0.67945 0.3048)
			(end 0.67945 -0.305054)
			(stroke
				(width 0.1)
				(type default)
			)
			(layer "B.Fab")
		)
		(fp_line
			(start -0.120396 0.2794)
			(end 0.12065 0.2794)
			(stroke
				(width 0.1)
				(type default)
			)
			(layer "B.Fab")
		)
		(fp_line
			(start 0.12065 0.2794)
			(end 0.12065 0.3048)
			(stroke
				(width 0.1)
				(type default)
			)
			(layer "B.Fab")
		)
		(fp_line
			(start -0.12065 -0.2794)
			(end -0.12065 -0.3048)
			(stroke
				(width 0.1)
				(type default)
			)
			(layer "B.Fab")
		)
		(fp_line
			(start 0.12065 -0.2794)
			(end -0.12065 -0.2794)
			(stroke
				(width 0.1)
				(type default)
			)
			(layer "B.Fab")
		)
		(fp_line
			(start -0.67945 -0.3048)
			(end -0.67945 0.3048)
			(stroke
				(width 0.1)
				(type default)
			)
			(layer "B.Fab")
		)
		(fp_line
			(start -0.12065 -0.3048)
			(end -0.67945 -0.3048)
			(stroke
				(width 0.1)
				(type default)
			)
			(layer "B.Fab")
		)
		(fp_line
			(start 0.12065 -0.305054)
			(end 0.12065 -0.2794)
			(stroke
				(width 0.1)
				(type default)
			)
			(layer "B.Fab")
		)
		(fp_line
			(start 0.67945 -0.305054)
			(end 0.12065 -0.305054)
			(stroke
				(width 0.1)
				(type default)
			)
			(layer "B.Fab")
		)
		(pad "1" smd circle
			(at 0.40005 0 90)
			(size 0 0)
			(layers "B.Cu" "B.Mask" "B.Paste")
			(net "SMB_NIC0_SDA")
		)
		(pad "2" smd circle
			(at -0.40005 0 90)
			(size 0 0)
			(layers "B.Cu" "B.Mask" "B.Paste")
			(net "SMB_NIC0_R_SDA")
		)
	)
	(footprint ""
		(layer "B.Cu")
		(at 412.699962 -299.699934 -90)
		(property "Reference" "C2005"
			(at 0 0 90)
			(layer "B.SilkS")
			(hide yes)
			(effects
				(font
					(size 1.27 1.27)
				)
				(justify mirror)
			)
		)
		(property "Value" ""
			(at 0 0 90)
			(layer "B.Fab")
			(effects
				(font
					(size 1.27 1.27)
				)
				(justify mirror)
			)
		)
		(duplicate_pad_numbers_are_jumpers no)
		(fp_line
			(start -0.299974 0.150114)
			(end 0.299974 0.150114)
			(stroke
				(width 0.1)
				(type default)
			)
			(layer "B.Fab")
		)
		(fp_line
			(start 0.299974 0.150114)
			(end 0.299974 -0.150114)
			(stroke
				(width 0.1)
				(type default)
			)
			(layer "B.Fab")
		)
		(fp_line
			(start -0.299974 -0.150114)
			(end -0.299974 0.150114)
			(stroke
				(width 0.1)
				(type default)
			)
			(layer "B.Fab")
		)
		(fp_line
			(start 0.299974 -0.150114)
			(end -0.299974 -0.150114)
			(stroke
				(width 0.1)
				(type default)
			)
			(layer "B.Fab")
		)
		(pad "1" smd rect
			(at 0.2667 0 90)
			(size 0.3048 0.381)
			(layers "B.Cu" "B.Mask" "B.Paste")
			(net "P0V8_SERDES_VDDA_PEX3")
		)
		(pad "2" smd rect
			(at -0.2667 0 90)
			(size 0.3048 0.381)
			(layers "B.Cu" "B.Mask" "B.Paste")
			(net "GND")
		)
	)
	(footprint ""
		(layer "B.Cu")
		(at 131.402328 -325.30923 -90)
		(property "Reference" "C4272"
			(at 0 0 90)
			(layer "B.SilkS")
			(hide yes)
			(effects
				(font
					(size 1.27 1.27)
				)
				(justify mirror)
			)
		)
		(property "Value" ""
			(at 0 0 90)
			(layer "B.Fab")
			(effects
				(font
					(size 1.27 1.27)
				)
				(justify mirror)
			)
		)
		(duplicate_pad_numbers_are_jumpers no)
		(fp_line
			(start -1.2954 0.5842)
			(end 1.2954 0.5842)
			(stroke
				(width 0.1524)
				(type default)
			)
			(layer "B.SilkS")
		)
		(fp_line
			(start 1.2954 0.5842)
			(end 1.2954 -0.5842)
			(stroke
				(width 0.1524)
				(type default)
			)
			(layer "B.SilkS")
		)
		(fp_line
			(start -1.2954 -0.5842)
			(end -1.2954 0.5842)
			(stroke
				(width 0.1524)
				(type default)
			)
			(layer "B.SilkS")
		)
		(fp_line
			(start 1.2954 -0.5842)
			(end -1.2954 -0.5842)
			(stroke
				(width 0.1524)
				(type default)
			)
			(layer "B.SilkS")
		)
		(fp_line
			(start -0.8636 0.4572)
			(end 0.8636 0.4572)
			(stroke
				(width 0.1)
				(type default)
			)
			(layer "B.Fab")
		)
		(fp_line
			(start 0.8636 0.4572)
			(end 0.8636 0.4064)
			(stroke
				(width 0.1)
				(type default)
			)
			(layer "B.Fab")
		)
		(fp_line
			(start -1.1938 0.4064)
			(end -0.8636 0.4064)
			(stroke
				(width 0.1)
				(type default)
			)
			(layer "B.Fab")
		)
		(fp_line
			(start -0.8636 0.4064)
			(end -0.8636 0.4572)
			(stroke
				(width 0.1)
				(type default)
			)
			(layer "B.Fab")
		)
		(fp_line
			(start 0.8636 0.4064)
			(end 1.1938 0.4064)
			(stroke
				(width 0.1)
				(type default)
			)
			(layer "B.Fab")
		)
		(fp_line
			(start 1.1938 0.4064)
			(end 1.1938 -0.4064)
			(stroke
				(width 0.1)
				(type default)
			)
			(layer "B.Fab")
		)
		(fp_line
			(start -1.1938 -0.4064)
			(end -1.1938 0.4064)
			(stroke
				(width 0.1)
				(type default)
			)
			(layer "B.Fab")
		)
		(fp_line
			(start -0.8636 -0.4064)
			(end -1.1938 -0.4064)
			(stroke
				(width 0.1)
				(type default)
			)
			(layer "B.Fab")
		)
		(fp_line
			(start 0.8636 -0.4064)
			(end 0.8636 -0.4572)
			(stroke
				(width 0.1)
				(type default)
			)
			(layer "B.Fab")
		)
		(fp_line
			(start 1.1938 -0.4064)
			(end 0.8636 -0.4064)
			(stroke
				(width 0.1)
				(type default)
			)
			(layer "B.Fab")
		)
		(fp_line
			(start -0.8636 -0.4572)
			(end -0.8636 -0.4064)
			(stroke
				(width 0.1)
				(type default)
			)
			(layer "B.Fab")
		)
		(fp_line
			(start 0.8636 -0.4572)
			(end -0.8636 -0.4572)
			(stroke
				(width 0.1)
				(type default)
			)
			(layer "B.Fab")
		)
		(pad "1" smd rect
			(at 0.7366 0 180)
			(size 0.7112 0.8128)
			(layers "B.Cu" "B.Mask" "B.Paste")
			(net "P0V8_SERDES_VDDA_PEX1_C10")
		)
		(pad "2" smd rect
			(at -0.7366 0 180)
			(size 0.7112 0.8128)
			(layers "B.Cu" "B.Mask" "B.Paste")
			(net "GND")
		)
	)
	(footprint ""
		(layer "B.Cu")
		(at 411.301438 -305.399948 -90)
		(property "Reference" "C3485"
			(at 0 0 90)
			(layer "B.SilkS")
			(hide yes)
			(effects
				(font
					(size 1.27 1.27)
				)
				(justify mirror)
			)
		)
		(property "Value" ""
			(at 0 0 90)
			(layer "B.Fab")
			(effects
				(font
					(size 1.27 1.27)
				)
				(justify mirror)
			)
		)
		(duplicate_pad_numbers_are_jumpers no)
		(fp_line
			(start -0.299974 0.150114)
			(end 0.299974 0.150114)
			(stroke
				(width 0.1)
				(type default)
			)
			(layer "B.Fab")
		)
		(fp_line
			(start 0.299974 0.150114)
			(end 0.299974 -0.150114)
			(stroke
				(width 0.1)
				(type default)
			)
			(layer "B.Fab")
		)
		(fp_line
			(start -0.299974 -0.150114)
			(end -0.299974 0.150114)
			(stroke
				(width 0.1)
				(type default)
			)
			(layer "B.Fab")
		)
		(fp_line
			(start 0.299974 -0.150114)
			(end -0.299974 -0.150114)
			(stroke
				(width 0.1)
				(type default)
			)
			(layer "B.Fab")
		)
		(pad "1" smd rect
			(at 0.2667 0 90)
			(size 0.3048 0.381)
			(layers "B.Cu" "B.Mask" "B.Paste")
			(net "P1V25_SERDES_VDDPLL_PEX3")
		)
		(pad "2" smd rect
			(at -0.2667 0 90)
			(size 0.3048 0.381)
			(layers "B.Cu" "B.Mask" "B.Paste")
			(net "GND")
		)
	)
	(footprint ""
		(layer "B.Cu")
		(at 402.724874 -297.79976 -90)
		(property "Reference" "C1907"
			(at 0 0 90)
			(layer "B.SilkS")
			(hide yes)
			(effects
				(font
					(size 1.27 1.27)
				)
				(justify mirror)
			)
		)
		(property "Value" ""
			(at 0 0 90)
			(layer "B.Fab")
			(effects
				(font
					(size 1.27 1.27)
				)
				(justify mirror)
			)
		)
		(duplicate_pad_numbers_are_jumpers no)
		(fp_line
			(start -0.299974 0.150114)
			(end 0.299974 0.150114)
			(stroke
				(width 0.1)
				(type default)
			)
			(layer "B.Fab")
		)
		(fp_line
			(start 0.299974 0.150114)
			(end 0.299974 -0.150114)
			(stroke
				(width 0.1)
				(type default)
			)
			(layer "B.Fab")
		)
		(fp_line
			(start -0.299974 -0.150114)
			(end -0.299974 0.150114)
			(stroke
				(width 0.1)
				(type default)
			)
			(layer "B.Fab")
		)
		(fp_line
			(start 0.299974 -0.150114)
			(end -0.299974 -0.150114)
			(stroke
				(width 0.1)
				(type default)
			)
			(layer "B.Fab")
		)
		(pad "1" smd rect
			(at 0.2667 0 90)
			(size 0.3048 0.381)
			(layers "B.Cu" "B.Mask" "B.Paste")
			(net "P0V8_PEX3")
		)
		(pad "2" smd rect
			(at -0.2667 0 90)
			(size 0.3048 0.381)
			(layers "B.Cu" "B.Mask" "B.Paste")
			(net "GND")
		)
	)
	(footprint ""
		(layer "B.Cu")
		(at 212.585808 -239.851692 90)
		(property "Reference" "R1544"
			(at 0 0 90)
			(layer "B.SilkS")
			(hide yes)
			(effects
				(font
					(size 1.27 1.27)
				)
				(justify mirror)
			)
		)
		(property "Value" ""
			(at 0 0 90)
			(layer "B.Fab")
			(effects
				(font
					(size 1.27 1.27)
				)
				(justify mirror)
			)
		)
		(duplicate_pad_numbers_are_jumpers no)
		(fp_line
			(start 0.7874 -0.4064)
			(end -0.7874 -0.4064)
			(stroke
				(width 0.1524)
				(type default)
			)
			(layer "B.SilkS")
		)
		(fp_line
			(start -0.7874 -0.4064)
			(end -0.7874 0.4064)
			(stroke
				(width 0.1524)
				(type default)
			)
			(layer "B.SilkS")
		)
		(fp_line
			(start 0.7874 0.4064)
			(end 0.7874 -0.4064)
			(stroke
				(width 0.1524)
				(type default)
			)
			(layer "B.SilkS")
		)
		(fp_line
			(start -0.7874 0.4064)
			(end 0.7874 0.4064)
			(stroke
				(width 0.1524)
				(type default)
			)
			(layer "B.SilkS")
		)
		(fp_line
			(start 0.67945 -0.305054)
			(end 0.12065 -0.305054)
			(stroke
				(width 0.1)
				(type default)
			)
			(layer "B.Fab")
		)
		(fp_line
			(start 0.12065 -0.305054)
			(end 0.12065 -0.2794)
			(stroke
				(width 0.1)
				(type default)
			)
			(layer "B.Fab")
		)
		(fp_line
			(start -0.12065 -0.3048)
			(end -0.67945 -0.3048)
			(stroke
				(width 0.1)
				(type default)
			)
			(layer "B.Fab")
		)
		(fp_line
			(start -0.67945 -0.3048)
			(end -0.67945 0.3048)
			(stroke
				(width 0.1)
				(type default)
			)
			(layer "B.Fab")
		)
		(fp_line
			(start 0.12065 -0.2794)
			(end -0.12065 -0.2794)
			(stroke
				(width 0.1)
				(type default)
			)
			(layer "B.Fab")
		)
		(fp_line
			(start -0.12065 -0.2794)
			(end -0.12065 -0.3048)
			(stroke
				(width 0.1)
				(type default)
			)
			(layer "B.Fab")
		)
		(fp_line
			(start 0.12065 0.2794)
			(end 0.12065 0.3048)
			(stroke
				(width 0.1)
				(type default)
			)
			(layer "B.Fab")
		)
		(fp_line
			(start -0.120396 0.2794)
			(end 0.12065 0.2794)
			(stroke
				(width 0.1)
				(type default)
			)
			(layer "B.Fab")
		)
		(fp_line
			(start 0.67945 0.3048)
			(end 0.67945 -0.305054)
			(stroke
				(width 0.1)
				(type default)
			)
			(layer "B.Fab")
		)
		(fp_line
			(start 0.12065 0.3048)
			(end 0.67945 0.3048)
			(stroke
				(width 0.1)
				(type default)
			)
			(layer "B.Fab")
		)
		(fp_line
			(start -0.120396 0.3048)
			(end -0.120396 0.2794)
			(stroke
				(width 0.1)
				(type default)
			)
			(layer "B.Fab")
		)
		(fp_line
			(start -0.67945 0.3048)
			(end -0.120396 0.3048)
			(stroke
				(width 0.1)
				(type default)
			)
			(layer "B.Fab")
		)
		(pad "1" smd circle
			(at 0.40005 0 270)
			(size 0 0)
			(layers "B.Cu" "B.Mask" "B.Paste")
			(net "SMB_PEX_R_SDA")
		)
		(pad "2" smd circle
			(at -0.40005 0 270)
			(size 0 0)
			(layers "B.Cu" "B.Mask" "B.Paste")
			(net "SMB_PEX_LS_SDA")
		)
	)
)
